(kicad_pcb
	(version 20221018)
	(generator pcbnew)
	(general
    (thickness 1.586)
  )
	(paper "A4")
	(title_block
    (date "2024-03-26")
    (rev "1.1.3")
		(comment 9 "footprints 8-9 of 146")
	)
	(layers
    (0 "F.Cu" signal)
    (1 "In1.Cu" power)
    (2 "In2.Cu" power)
    (31 "B.Cu" signal)
    (32 "B.Adhes" user "B.Adhesive")
    (33 "F.Adhes" user "F.Adhesive")
    (34 "B.Paste" user)
    (35 "F.Paste" user)
    (36 "B.SilkS" user "B.Silkscreen")
    (37 "F.SilkS" user "F.Silkscreen")
    (38 "B.Mask" user)
    (39 "F.Mask" user)
    (40 "Dwgs.User" user "User.Drawings")
    (41 "Cmts.User" user "User.Comments")
    (42 "Eco1.User" user "User.Eco1")
    (43 "Eco2.User" user "User.Eco2")
    (44 "Edge.Cuts" user)
    (45 "Margin" user)
    (46 "B.CrtYd" user "B.Courtyard")
    (47 "F.CrtYd" user "F.Courtyard")
    (48 "B.Fab" user)
    (49 "F.Fab" user)
  )
	(footprint "scalenode-cm4-baseboard-footprints:R_0402_1005Metric" (layer "F.Cu")
    (at 93.29 58.106 180)
    (descr "Resistor SMD 0402")
    (tags "resistor SMD 0402")
    (property "Author" "Antmicro")
    (property "License" "Apache-2.0")
    (property "MPN" "CR0402-FX-2200GLF")
    (property "Manufacturer" "Bourns")
    (property "Sheetfile" "poe.kicad_sch")
    (property "Sheetname" "PoE")
    (property "Tolerance" "1%")
    (property "Val" "220R")
    (property "ki_description" "220R resistor in 0402 package with 1% tolerance")
    (attr smd)
    (fp_text reference "R22" (at 0.815 0.531 180) (layer "F.SilkS")
        (effects (font (size 0.7 0.7) (thickness 0.15)) (justify left bottom))
    )
    (fp_text value "R_220R_0402" (at 4.39 -2.094 180) (layer "F.Fab")
        (effects (font (size 0.7 0.7) (thickness 0.15)) (justify left bottom))
    )
    (fp_text user "${REFERENCE}" (at -0.95 3.168 180) (layer "F.Fab") hide
        (effects (font (size 0.7 0.7) (thickness 0.15)) (justify left bottom))
    )
    (fp_text user "License: Apache-2.0" (at -0.95 5.169 180) (layer "F.Fab") hide
        (effects (font (size 0.7 0.7) (thickness 0.15)) (justify left bottom))
    )
    (fp_text user "Author: Antmicro" (at -0.95 4.169 180) (layer "F.Fab") hide
        (effects (font (size 0.7 0.7) (thickness 0.15)) (justify left bottom))
    )
    (fp_rect (start -0.95 -0.48) (end 0.95 0.48)
      (stroke (width 0.05) (type solid)) (fill none) (layer "F.CrtYd"))
    (fp_rect (start -0.5 -0.25) (end 0.5 0.25)
      (stroke (width 0.15) (type solid)) (fill none) (layer "F.Fab"))
    (pad "1" smd roundrect (at -0.485 0 180) (size 0.59 0.64) (layers "F.Cu" "F.Paste" "F.Mask") (roundrect_rratio 0.25)
      (net 226 "Net-(J6-Pad12)") (pintype "passive"))
    (pad "2" smd roundrect (at 0.485 0 180) (size 0.59 0.64) (layers "F.Cu" "F.Paste" "F.Mask") (roundrect_rratio 0.25)
      (net 232 "3V3_RPi") (pintype "passive"))
  )
	(footprint "scalenode-cm4-baseboard-footprints:R_0402_1005Metric" (layer "F.Cu")
    (at 91.25 58.106)
    (descr "Resistor SMD 0402")
    (tags "resistor SMD 0402")
    (property "Author" "Antmicro")
    (property "License" "Apache-2.0")
    (property "MPN" "CR0402-FX-2200GLF")
    (property "Manufacturer" "Bourns")
    (property "Sheetfile" "poe.kicad_sch")
    (property "Sheetname" "PoE")
    (property "Tolerance" "1%")
    (property "Val" "220R")
    (property "ki_description" "220R resistor in 0402 package with 1% tolerance")
    (attr smd)
    (fp_text reference "R21" (at -1.5 -0.531) (layer "F.SilkS")
        (effects (font (size 0.7 0.7) (thickness 0.15)) (justify left bottom))
    )
    (fp_text value "R_220R_0402" (at 0 1.4) (layer "F.Fab")
        (effects (font (size 0.7 0.7) (thickness 0.15)) (justify left bottom))
    )
    (fp_text user "License: Apache-2.0" (at -0.95 5.169) (layer "F.Fab") hide
        (effects (font (size 0.7 0.7) (thickness 0.15)) (justify left bottom))
    )
    (fp_text user "Author: Antmicro" (at -0.95 4.169) (layer "F.Fab") hide
        (effects (font (size 0.7 0.7) (thickness 0.15)) (justify left bottom))
    )
    (fp_text user "${REFERENCE}" (at -0.95 3.168) (layer "F.Fab") hide
        (effects (font (size 0.7 0.7) (thickness 0.15)) (justify left bottom))
    )
    (fp_rect (start -0.95 -0.48) (end 0.95 0.48)
      (stroke (width 0.05) (type solid)) (fill none) (layer "F.CrtYd"))
    (fp_rect (start -0.5 -0.25) (end 0.5 0.25)
      (stroke (width 0.15) (type solid)) (fill none) (layer "F.Fab"))
    (pad "1" smd roundrect (at -0.485 0) (size 0.59 0.64) (layers "F.Cu" "F.Paste" "F.Mask") (roundrect_rratio 0.25)
      (net 225 "Net-(J6-Pad10)") (pintype "passive"))
    (pad "2" smd roundrect (at 0.485 0) (size 0.59 0.64) (layers "F.Cu" "F.Paste" "F.Mask") (roundrect_rratio 0.25)
      (net 232 "3V3_RPi") (pintype "passive"))
  )
)
